(kicad_pcb
	(version 20260206)
	(generator "pcbnew")
	(generator_version "10.0")
	(general
		(thickness 1.6)
		(legacy_teardrops no)
	)
	(paper "A4")
	(title_block
		(title "04192023_DAF0TMB3IC0_F0TG_MB_C_brd_V02_OCP.brd")
		(comment 1 "Grand Teton / footprints 4547-4552 of 8354")
	)
	(layers
		(0 "F.Cu" signal "TOP")
		(4 "In1.Cu" signal "GND")
		(6 "In2.Cu" signal "IN1")
		(8 "In3.Cu" signal "GND1")
		(10 "In4.Cu" signal "IN2")
		(12 "In5.Cu" signal "GND2")
		(14 "In6.Cu" signal "IN3")
		(16 "In7.Cu" signal "GND3")
		(18 "In8.Cu" signal "VCC")
		(20 "In9.Cu" signal "VCC1")
		(22 "In10.Cu" signal "GND4")
		(24 "In11.Cu" signal "IN4")
		(26 "In12.Cu" signal "GND5")
		(28 "In13.Cu" signal "IN5")
		(30 "In14.Cu" signal "GND6")
		(32 "In15.Cu" signal "IN6")
		(34 "In16.Cu" signal "GND7")
		(2 "B.Cu" signal "BOTTOM")
		(9 "F.Adhes" user "F.Adhesive")
		(11 "B.Adhes" user "B.Adhesive")
		(13 "F.Paste" user "Package Geometry/Pastemask Top")
		(15 "B.Paste" user "Package Geometry/Pastemask Bottom")
		(5 "F.SilkS" user "Ref Des/Silkscreen Top")
		(7 "B.SilkS" user "Ref Des/Silkscreen Bottom")
		(1 "F.Mask" user "Board Geometry/Soldermask Top")
		(3 "B.Mask" user "Board Geometry/Soldermask Bottom")
		(17 "Dwgs.User" user "User.Drawings")
		(19 "Cmts.User" user "User.Comments")
		(21 "Eco1.User" user "User.Eco1")
		(23 "Eco2.User" user "User.Eco2")
		(25 "Edge.Cuts" user "Board Geometry/Outline")
		(27 "Margin" user)
		(31 "F.CrtYd" user "Package Geometry/Place Bound Top")
		(29 "B.CrtYd" user "Package Geometry/Place Bound Bottom")
		(35 "F.Fab" user "Ref Des/Assembly Top")
		(33 "B.Fab" user "Ref Des/Assembly Bottom")
	)
	(footprint ""
		(layer "F.Cu")
		(at 449.795392 -52.84851 90)
		(property "Reference" "PC8567"
			(at 0 0 90)
			(layer "F.SilkS")
			(hide yes)
			(effects
				(font
					(size 1.27 1.27)
				)
			)
		)
		(property "Value" ""
			(at 0 0 90)
			(layer "F.Fab")
			(effects
				(font
					(size 1.27 1.27)
				)
			)
		)
		(duplicate_pad_numbers_are_jumpers no)
		(fp_line
			(start 1.524 -0.762)
			(end 1.524 0.762)
			(stroke
				(width 0.1524)
				(type default)
			)
			(layer "F.SilkS")
		)
		(fp_line
			(start -1.524 -0.762)
			(end 1.524 -0.762)
			(stroke
				(width 0.1524)
				(type default)
			)
			(layer "F.SilkS")
		)
		(fp_line
			(start 1.524 0.762)
			(end -1.524 0.762)
			(stroke
				(width 0.1524)
				(type default)
			)
			(layer "F.SilkS")
		)
		(fp_line
			(start -1.524 0.762)
			(end -1.524 -0.762)
			(stroke
				(width 0.1524)
				(type default)
			)
			(layer "F.SilkS")
		)
		(fp_line
			(start 1.1049 -0.724916)
			(end -1.1049 -0.724916)
			(stroke
				(width 0.1)
				(type default)
			)
			(layer "F.Fab")
		)
		(fp_line
			(start -1.1049 -0.724916)
			(end -1.1049 0.724916)
			(stroke
				(width 0.1)
				(type default)
			)
			(layer "F.Fab")
		)
		(fp_line
			(start 1.1049 0.724916)
			(end 1.1049 -0.724916)
			(stroke
				(width 0.1)
				(type default)
			)
			(layer "F.Fab")
		)
		(fp_line
			(start -1.1049 0.724916)
			(end 1.1049 0.724916)
			(stroke
				(width 0.1)
				(type default)
			)
			(layer "F.Fab")
		)
		(pad "1" smd rect
			(at -0.889 0 270)
			(size 1.016 1.27)
			(layers "F.Cu" "F.Mask" "F.Paste")
			(net "SW_P3V3_AUX_FLT")
		)
		(pad "2" smd rect
			(at 0.889 0 270)
			(size 1.016 1.27)
			(layers "F.Cu" "F.Mask" "F.Paste")
			(net "GND")
		)
	)
	(footprint ""
		(layer "F.Cu")
		(at 325.545958 -193.925952 -90)
		(property "Reference" "R247"
			(at 0 0 270)
			(layer "F.SilkS")
			(hide yes)
			(effects
				(font
					(size 1.27 1.27)
				)
			)
		)
		(property "Value" ""
			(at 0 0 270)
			(layer "F.Fab")
			(effects
				(font
					(size 1.27 1.27)
				)
			)
		)
		(duplicate_pad_numbers_are_jumpers no)
		(fp_line
			(start -0.7874 0.4064)
			(end -0.7874 -0.4064)
			(stroke
				(width 0.1524)
				(type default)
			)
			(layer "F.SilkS")
		)
		(fp_line
			(start 0.7874 0.4064)
			(end -0.7874 0.4064)
			(stroke
				(width 0.1524)
				(type default)
			)
			(layer "F.SilkS")
		)
		(fp_line
			(start -0.7874 -0.4064)
			(end 0.7874 -0.4064)
			(stroke
				(width 0.1524)
				(type default)
			)
			(layer "F.SilkS")
		)
		(fp_line
			(start 0.7874 -0.4064)
			(end 0.7874 0.4064)
			(stroke
				(width 0.1524)
				(type default)
			)
			(layer "F.SilkS")
		)
		(fp_line
			(start -0.67945 0.3048)
			(end -0.67945 -0.305054)
			(stroke
				(width 0.1)
				(type default)
			)
			(layer "F.Fab")
		)
		(fp_line
			(start -0.12065 0.3048)
			(end -0.67945 0.3048)
			(stroke
				(width 0.1)
				(type default)
			)
			(layer "F.Fab")
		)
		(fp_line
			(start 0.120396 0.3048)
			(end 0.120396 0.2794)
			(stroke
				(width 0.1)
				(type default)
			)
			(layer "F.Fab")
		)
		(fp_line
			(start 0.67945 0.3048)
			(end 0.120396 0.3048)
			(stroke
				(width 0.1)
				(type default)
			)
			(layer "F.Fab")
		)
		(fp_line
			(start -0.12065 0.2794)
			(end -0.12065 0.3048)
			(stroke
				(width 0.1)
				(type default)
			)
			(layer "F.Fab")
		)
		(fp_line
			(start 0.120396 0.2794)
			(end -0.12065 0.2794)
			(stroke
				(width 0.1)
				(type default)
			)
			(layer "F.Fab")
		)
		(fp_line
			(start -0.12065 -0.2794)
			(end 0.12065 -0.2794)
			(stroke
				(width 0.1)
				(type default)
			)
			(layer "F.Fab")
		)
		(fp_line
			(start 0.12065 -0.2794)
			(end 0.12065 -0.3048)
			(stroke
				(width 0.1)
				(type default)
			)
			(layer "F.Fab")
		)
		(fp_line
			(start 0.12065 -0.3048)
			(end 0.67945 -0.3048)
			(stroke
				(width 0.1)
				(type default)
			)
			(layer "F.Fab")
		)
		(fp_line
			(start 0.67945 -0.3048)
			(end 0.67945 0.3048)
			(stroke
				(width 0.1)
				(type default)
			)
			(layer "F.Fab")
		)
		(fp_line
			(start -0.67945 -0.305054)
			(end -0.12065 -0.305054)
			(stroke
				(width 0.1)
				(type default)
			)
			(layer "F.Fab")
		)
		(fp_line
			(start -0.12065 -0.305054)
			(end -0.12065 -0.2794)
			(stroke
				(width 0.1)
				(type default)
			)
			(layer "F.Fab")
		)
		(pad "1" smd circle
			(at -0.40005 0 270)
			(size 0 0)
			(layers "F.Cu" "F.Mask" "F.Paste")
			(net "APML_CPU0_ALERT_N")
		)
		(pad "2" smd circle
			(at 0.40005 0 270)
			(size 0 0)
			(layers "F.Cu" "F.Mask" "F.Paste")
			(net "APML_CPU0_ALERT_R_N")
		)
	)
	(footprint ""
		(layer "F.Cu")
		(at 87.88146 -339.630258 90)
		(property "Reference" "PR258"
			(at 0 0 90)
			(layer "F.SilkS")
			(hide yes)
			(effects
				(font
					(size 1.27 1.27)
				)
			)
		)
		(property "Value" ""
			(at 0 0 90)
			(layer "F.Fab")
			(effects
				(font
					(size 1.27 1.27)
				)
			)
		)
		(duplicate_pad_numbers_are_jumpers no)
		(fp_line
			(start 0.7874 -0.4064)
			(end 0.7874 0.4064)
			(stroke
				(width 0.1524)
				(type default)
			)
			(layer "F.SilkS")
		)
		(fp_line
			(start -0.7874 -0.4064)
			(end 0.7874 -0.4064)
			(stroke
				(width 0.1524)
				(type default)
			)
			(layer "F.SilkS")
		)
		(fp_line
			(start 0.7874 0.4064)
			(end -0.7874 0.4064)
			(stroke
				(width 0.1524)
				(type default)
			)
			(layer "F.SilkS")
		)
		(fp_line
			(start -0.7874 0.4064)
			(end -0.7874 -0.4064)
			(stroke
				(width 0.1524)
				(type default)
			)
			(layer "F.SilkS")
		)
		(fp_line
			(start -0.12065 -0.305054)
			(end -0.12065 -0.2794)
			(stroke
				(width 0.1)
				(type default)
			)
			(layer "F.Fab")
		)
		(fp_line
			(start -0.67945 -0.305054)
			(end -0.12065 -0.305054)
			(stroke
				(width 0.1)
				(type default)
			)
			(layer "F.Fab")
		)
		(fp_line
			(start 0.67945 -0.3048)
			(end 0.67945 0.3048)
			(stroke
				(width 0.1)
				(type default)
			)
			(layer "F.Fab")
		)
		(fp_line
			(start 0.12065 -0.3048)
			(end 0.67945 -0.3048)
			(stroke
				(width 0.1)
				(type default)
			)
			(layer "F.Fab")
		)
		(fp_line
			(start 0.12065 -0.2794)
			(end 0.12065 -0.3048)
			(stroke
				(width 0.1)
				(type default)
			)
			(layer "F.Fab")
		)
		(fp_line
			(start -0.12065 -0.2794)
			(end 0.12065 -0.2794)
			(stroke
				(width 0.1)
				(type default)
			)
			(layer "F.Fab")
		)
		(fp_line
			(start 0.120396 0.2794)
			(end -0.12065 0.2794)
			(stroke
				(width 0.1)
				(type default)
			)
			(layer "F.Fab")
		)
		(fp_line
			(start -0.12065 0.2794)
			(end -0.12065 0.3048)
			(stroke
				(width 0.1)
				(type default)
			)
			(layer "F.Fab")
		)
		(fp_line
			(start 0.67945 0.3048)
			(end 0.120396 0.3048)
			(stroke
				(width 0.1)
				(type default)
			)
			(layer "F.Fab")
		)
		(fp_line
			(start 0.120396 0.3048)
			(end 0.120396 0.2794)
			(stroke
				(width 0.1)
				(type default)
			)
			(layer "F.Fab")
		)
		(fp_line
			(start -0.12065 0.3048)
			(end -0.67945 0.3048)
			(stroke
				(width 0.1)
				(type default)
			)
			(layer "F.Fab")
		)
		(fp_line
			(start -0.67945 0.3048)
			(end -0.67945 -0.305054)
			(stroke
				(width 0.1)
				(type default)
			)
			(layer "F.Fab")
		)
		(pad "1" smd circle
			(at -0.40005 0 90)
			(size 0 0)
			(layers "F.Cu" "F.Mask" "F.Paste")
			(net "SW_PVDDCR_CPU1_P1_BOOT1")
		)
		(pad "2" smd circle
			(at 0.40005 0 90)
			(size 0 0)
			(layers "F.Cu" "F.Mask" "F.Paste")
			(net "SW_PVDDCR_CPU1_P1_BOOT1_R")
		)
	)
	(footprint ""
		(layer "F.Cu")
		(at 304.57521 -351.050352)
		(property "Reference" "PC178_4"
			(at 0 0 0)
			(layer "F.SilkS")
			(hide yes)
			(effects
				(font
					(size 1.27 1.27)
				)
			)
		)
		(property "Value" ""
			(at 0 0 0)
			(layer "F.Fab")
			(effects
				(font
					(size 1.27 1.27)
				)
			)
		)
		(duplicate_pad_numbers_are_jumpers no)
		(fp_line
			(start -0.7874 -0.4064)
			(end 0.7874 -0.4064)
			(stroke
				(width 0.1524)
				(type default)
			)
			(layer "F.SilkS")
		)
		(fp_line
			(start -0.7874 0.4064)
			(end -0.7874 -0.4064)
			(stroke
				(width 0.1524)
				(type default)
			)
			(layer "F.SilkS")
		)
		(fp_line
			(start 0.7874 -0.4064)
			(end 0.7874 0.4064)
			(stroke
				(width 0.1524)
				(type default)
			)
			(layer "F.SilkS")
		)
		(fp_line
			(start 0.7874 0.4064)
			(end -0.7874 0.4064)
			(stroke
				(width 0.1524)
				(type default)
			)
			(layer "F.SilkS")
		)
		(fp_line
			(start -0.67945 -0.305054)
			(end -0.12065 -0.305054)
			(stroke
				(width 0.1)
				(type default)
			)
			(layer "F.Fab")
		)
		(fp_line
			(start -0.67945 0.3048)
			(end -0.67945 -0.305054)
			(stroke
				(width 0.1)
				(type default)
			)
			(layer "F.Fab")
		)
		(fp_line
			(start -0.12065 -0.305054)
			(end -0.12065 -0.2794)
			(stroke
				(width 0.1)
				(type default)
			)
			(layer "F.Fab")
		)
		(fp_line
			(start -0.12065 -0.2794)
			(end 0.12065 -0.2794)
			(stroke
				(width 0.1)
				(type default)
			)
			(layer "F.Fab")
		)
		(fp_line
			(start -0.12065 0.2794)
			(end -0.12065 0.3048)
			(stroke
				(width 0.1)
				(type default)
			)
			(layer "F.Fab")
		)
		(fp_line
			(start -0.12065 0.3048)
			(end -0.67945 0.3048)
			(stroke
				(width 0.1)
				(type default)
			)
			(layer "F.Fab")
		)
		(fp_line
			(start 0.120396 0.2794)
			(end -0.12065 0.2794)
			(stroke
				(width 0.1)
				(type default)
			)
			(layer "F.Fab")
		)
		(fp_line
			(start 0.120396 0.3048)
			(end 0.120396 0.2794)
			(stroke
				(width 0.1)
				(type default)
			)
			(layer "F.Fab")
		)
		(fp_line
			(start 0.12065 -0.3048)
			(end 0.67945 -0.3048)
			(stroke
				(width 0.1)
				(type default)
			)
			(layer "F.Fab")
		)
		(fp_line
			(start 0.12065 -0.2794)
			(end 0.12065 -0.3048)
			(stroke
				(width 0.1)
				(type default)
			)
			(layer "F.Fab")
		)
		(fp_line
			(start 0.67945 -0.3048)
			(end 0.67945 0.3048)
			(stroke
				(width 0.1)
				(type default)
			)
			(layer "F.Fab")
		)
		(fp_line
			(start 0.67945 0.3048)
			(end 0.120396 0.3048)
			(stroke
				(width 0.1)
				(type default)
			)
			(layer "F.Fab")
		)
		(pad "1" smd circle
			(at -0.40005 0)
			(size 0 0)
			(layers "F.Cu" "F.Mask" "F.Paste")
			(net "SW_P12V_AUX_PVDDIO_P0_FLT")
		)
		(pad "2" smd circle
			(at 0.40005 0)
			(size 0 0)
			(layers "F.Cu" "F.Mask" "F.Paste")
			(net "GND")
		)
	)
	(footprint ""
		(layer "F.Cu")
		(at 166.937944 -348.284546)
		(property "Reference" "PC643"
			(at 0 0 0)
			(layer "F.SilkS")
			(hide yes)
			(effects
				(font
					(size 1.27 1.27)
				)
			)
		)
		(property "Value" ""
			(at 0 0 0)
			(layer "F.Fab")
			(effects
				(font
					(size 1.27 1.27)
				)
			)
		)
		(duplicate_pad_numbers_are_jumpers no)
		(fp_line
			(start -0.7874 -0.4064)
			(end 0.7874 -0.4064)
			(stroke
				(width 0.1524)
				(type default)
			)
			(layer "F.SilkS")
		)
		(fp_line
			(start -0.7874 0.4064)
			(end -0.7874 -0.4064)
			(stroke
				(width 0.1524)
				(type default)
			)
			(layer "F.SilkS")
		)
		(fp_line
			(start 0.7874 -0.4064)
			(end 0.7874 0.4064)
			(stroke
				(width 0.1524)
				(type default)
			)
			(layer "F.SilkS")
		)
		(fp_line
			(start 0.7874 0.4064)
			(end -0.7874 0.4064)
			(stroke
				(width 0.1524)
				(type default)
			)
			(layer "F.SilkS")
		)
		(fp_line
			(start -0.67945 -0.305054)
			(end -0.12065 -0.305054)
			(stroke
				(width 0.1)
				(type default)
			)
			(layer "F.Fab")
		)
		(fp_line
			(start -0.67945 0.3048)
			(end -0.67945 -0.305054)
			(stroke
				(width 0.1)
				(type default)
			)
			(layer "F.Fab")
		)
		(fp_line
			(start -0.12065 -0.305054)
			(end -0.12065 -0.2794)
			(stroke
				(width 0.1)
				(type default)
			)
			(layer "F.Fab")
		)
		(fp_line
			(start -0.12065 -0.2794)
			(end 0.12065 -0.2794)
			(stroke
				(width 0.1)
				(type default)
			)
			(layer "F.Fab")
		)
		(fp_line
			(start -0.12065 0.2794)
			(end -0.12065 0.3048)
			(stroke
				(width 0.1)
				(type default)
			)
			(layer "F.Fab")
		)
		(fp_line
			(start -0.12065 0.3048)
			(end -0.67945 0.3048)
			(stroke
				(width 0.1)
				(type default)
			)
			(layer "F.Fab")
		)
		(fp_line
			(start 0.120396 0.2794)
			(end -0.12065 0.2794)
			(stroke
				(width 0.1)
				(type default)
			)
			(layer "F.Fab")
		)
		(fp_line
			(start 0.120396 0.3048)
			(end 0.120396 0.2794)
			(stroke
				(width 0.1)
				(type default)
			)
			(layer "F.Fab")
		)
		(fp_line
			(start 0.12065 -0.3048)
			(end 0.67945 -0.3048)
			(stroke
				(width 0.1)
				(type default)
			)
			(layer "F.Fab")
		)
		(fp_line
			(start 0.12065 -0.2794)
			(end 0.12065 -0.3048)
			(stroke
				(width 0.1)
				(type default)
			)
			(layer "F.Fab")
		)
		(fp_line
			(start 0.67945 -0.3048)
			(end 0.67945 0.3048)
			(stroke
				(width 0.1)
				(type default)
			)
			(layer "F.Fab")
		)
		(fp_line
			(start 0.67945 0.3048)
			(end 0.120396 0.3048)
			(stroke
				(width 0.1)
				(type default)
			)
			(layer "F.Fab")
		)
		(pad "1" smd circle
			(at -0.40005 0)
			(size 0 0)
			(layers "F.Cu" "F.Mask" "F.Paste")
			(net "PVDD11_S3_P1_TEMP0")
		)
		(pad "2" smd circle
			(at 0.40005 0)
			(size 0 0)
			(layers "F.Cu" "F.Mask" "F.Paste")
			(net "GND")
		)
	)
	(footprint ""
		(layer "F.Cu")
		(at 189.80023 -35.017456 180)
		(property "Reference" "R1854"
			(at 0 0 180)
			(layer "F.SilkS")
			(hide yes)
			(effects
				(font
					(size 1.27 1.27)
				)
			)
		)
		(property "Value" ""
			(at 0 0 180)
			(layer "F.Fab")
			(effects
				(font
					(size 1.27 1.27)
				)
			)
		)
		(duplicate_pad_numbers_are_jumpers no)
		(fp_line
			(start 0.7874 0.4064)
			(end -0.7874 0.4064)
			(stroke
				(width 0.1524)
				(type default)
			)
			(layer "F.SilkS")
		)
		(fp_line
			(start 0.7874 -0.4064)
			(end 0.7874 0.4064)
			(stroke
				(width 0.1524)
				(type default)
			)
			(layer "F.SilkS")
		)
		(fp_line
			(start -0.7874 0.4064)
			(end -0.7874 -0.4064)
			(stroke
				(width 0.1524)
				(type default)
			)
			(layer "F.SilkS")
		)
		(fp_line
			(start -0.7874 -0.4064)
			(end 0.7874 -0.4064)
			(stroke
				(width 0.1524)
				(type default)
			)
			(layer "F.SilkS")
		)
		(fp_line
			(start 0.67945 0.3048)
			(end 0.120396 0.3048)
			(stroke
				(width 0.1)
				(type default)
			)
			(layer "F.Fab")
		)
		(fp_line
			(start 0.67945 -0.3048)
			(end 0.67945 0.3048)
			(stroke
				(width 0.1)
				(type default)
			)
			(layer "F.Fab")
		)
		(fp_line
			(start 0.12065 -0.2794)
			(end 0.12065 -0.3048)
			(stroke
				(width 0.1)
				(type default)
			)
			(layer "F.Fab")
		)
		(fp_line
			(start 0.12065 -0.3048)
			(end 0.67945 -0.3048)
			(stroke
				(width 0.1)
				(type default)
			)
			(layer "F.Fab")
		)
		(fp_line
			(start 0.120396 0.3048)
			(end 0.120396 0.2794)
			(stroke
				(width 0.1)
				(type default)
			)
			(layer "F.Fab")
		)
		(fp_line
			(start 0.120396 0.2794)
			(end -0.12065 0.2794)
			(stroke
				(width 0.1)
				(type default)
			)
			(layer "F.Fab")
		)
		(fp_line
			(start -0.12065 0.3048)
			(end -0.67945 0.3048)
			(stroke
				(width 0.1)
				(type default)
			)
			(layer "F.Fab")
		)
		(fp_line
			(start -0.12065 0.2794)
			(end -0.12065 0.3048)
			(stroke
				(width 0.1)
				(type default)
			)
			(layer "F.Fab")
		)
		(fp_line
			(start -0.12065 -0.2794)
			(end 0.12065 -0.2794)
			(stroke
				(width 0.1)
				(type default)
			)
			(layer "F.Fab")
		)
		(fp_line
			(start -0.12065 -0.305054)
			(end -0.12065 -0.2794)
			(stroke
				(width 0.1)
				(type default)
			)
			(layer "F.Fab")
		)
		(fp_line
			(start -0.67945 0.3048)
			(end -0.67945 -0.305054)
			(stroke
				(width 0.1)
				(type default)
			)
			(layer "F.Fab")
		)
		(fp_line
			(start -0.67945 -0.305054)
			(end -0.12065 -0.305054)
			(stroke
				(width 0.1)
				(type default)
			)
			(layer "F.Fab")
		)
		(pad "1" smd circle
			(at -0.40005 0 180)
			(size 0 0)
			(layers "F.Cu" "F.Mask" "F.Paste")
			(net "P3V3_AUX")
		)
		(pad "2" smd circle
			(at 0.40005 0 180)
			(size 0 0)
			(layers "F.Cu" "F.Mask" "F.Paste")
			(net "FM_SCM_PRSNT1_N")
		)
	)
)
